# BASEBOARD_FAB2 (Tioga Pass) — schematic netlist excerpt (pin names and nets, part order shuffled) for the footprints in the layout excerpt that follows; sources: Cadence DE-HDL packaged netlist, KiCad conversion of Wiwynn_Tioga_Pass_MB.brd

Q9W3  NPN  MMBT3904 IC  pkg SM  page 249
  B  = FM_TPM_PRES_RST
  E  = GND
  C  = RST_BMC_EXTRST_N

C6W2  CAP_A  0.1UF 16V 10% X7R  pkg 0402V  page 247 : A = P3V3_STBY ; B = GND
C6R14  CAP  10UF 16V 10% X6S  pkg 0805  page 214 : A = VR_FET_SW_P12V_STBY_PVCCIN_CPU0 ; B = GND

(kicad_pcb
	(version 20260206)
	(generator "pcbnew")
	(generator_version "10.0")
	(general
		(thickness 1.6)
		(legacy_teardrops no)
	)
	(paper "A4")
	(title_block
		(title "Wiwynn_Tioga_Pass_MB.brd")
		(comment 1 "Tioga Pass / footprints 2516-2518 of 4770")
	)
	(layers
		(0 "F.Cu" signal "TOP")
		(4 "In1.Cu" signal "L2GND")
		(6 "In2.Cu" signal "L3")
		(8 "In3.Cu" signal "L4GND")
		(10 "In4.Cu" signal "L5")
		(12 "In5.Cu" signal "L6GND")
		(14 "In6.Cu" signal "L7VCC")
		(16 "In7.Cu" signal "L8VCC")
		(18 "In8.Cu" signal "L9GND")
		(20 "In9.Cu" signal "L10")
		(22 "In10.Cu" signal "L11GND")
		(24 "In11.Cu" signal "L12")
		(26 "In12.Cu" signal "L13GND")
		(2 "B.Cu" signal "BOTTOM")
		(9 "F.Adhes" user "F.Adhesive")
		(11 "B.Adhes" user "B.Adhesive")
		(13 "F.Paste" user "Package Geometry/Pastemask Top")
		(15 "B.Paste" user "Package Geometry/Pastemask Bottom")
		(5 "F.SilkS" user "Ref Des/Silkscreen Top")
		(7 "B.SilkS" user "Ref Des/Silkscreen Bottom")
		(1 "F.Mask" user "Board Geometry/Soldermask Top")
		(3 "B.Mask" user "Board Geometry/Soldermask Bottom")
		(17 "Dwgs.User" user "User.Drawings")
		(19 "Cmts.User" user "User.Comments")
		(21 "Eco1.User" user "User.Eco1")
		(23 "Eco2.User" user "User.Eco2")
		(25 "Edge.Cuts" user "Board Geometry/Outline")
		(27 "Margin" user)
		(31 "F.CrtYd" user "Package Geometry/Place Bound Top")
		(29 "B.CrtYd" user "Package Geometry/Place Bound Bottom")
		(35 "F.Fab" user "Ref Des/Assembly Top")
		(33 "B.Fab" user "Ref Des/Assembly Bottom")
	)
	(footprint ""
		(layer "B.Cu")
		(at 399.4404 -74.168 90)
		(property "Reference" "C6W2"
			(at 0.8382 -0.67818 90)
			(unlocked yes)
			(layer "B.SilkS")
			(effects
				(font
					(size 0.4064 0.254)
					(thickness 0.1524)
				)
				(justify left mirror)
			)
		)
		(property "Value" ""
			(at 0 0 90)
			(layer "B.Fab")
			(effects
				(font
					(size 1.27 1.27)
				)
				(justify mirror)
			)
		)
		(duplicate_pad_numbers_are_jumpers no)
		(fp_poly
			(pts
				(xy -0.3048 -0.1016) (xy -0.3048 0.9906) (xy 0.3048 0.9906) (xy 0.3048 -0.1016)
			)
			(stroke
				(width 0)
				(type default)
			)
			(fill no)
			(layer "B.CrtYd")
		)
		(fp_line
			(start 0.3048 -0.1016)
			(end 0.3048 0.9906)
			(stroke
				(width 0.1)
				(type default)
			)
			(layer "B.Fab")
		)
		(fp_line
			(start -0.3048 -0.1016)
			(end 0.3048 -0.1016)
			(stroke
				(width 0.1)
				(type default)
			)
			(layer "B.Fab")
		)
		(fp_line
			(start 0.3048 0.9906)
			(end -0.3048 0.9906)
			(stroke
				(width 0.1)
				(type default)
			)
			(layer "B.Fab")
		)
		(fp_line
			(start -0.3048 0.9906)
			(end -0.3048 -0.1016)
			(stroke
				(width 0.1)
				(type default)
			)
			(layer "B.Fab")
		)
		(pad "1" smd rect
			(at 0 0 270)
			(size 0.508 0.508)
			(layers "B.Cu" "B.Mask" "B.Paste")
			(net "P3V3_STBY")
		)
		(pad "2" smd rect
			(at 0 0.889 270)
			(size 0.508 0.508)
			(layers "B.Cu" "B.Mask" "B.Paste")
			(net "GND")
		)
		(zone
			(layer "B.Cu")
			(hatch none 0.5)
			(connect_pads
				(clearance 0)
			)
			(min_thickness 0.25)
			(keepout
				(tracks allowed)
				(vias not_allowed)
				(pads allowed)
				(copperpour not_allowed)
				(footprints allowed)
			)
			(placement
				(enabled no)
				(sheetname "")
			)
			(fill
				(thermal_gap 0.5)
				(thermal_bridge_width 0.5)
				(island_removal_mode 0)
			)
			(polygon
				(pts
					(xy 399.6944 -74.422) (xy 399.6944 -73.914) (xy 400.0754 -73.914) (xy 400.0754 -74.422)
				)
			)
		)
		(zone
			(layer "B.Cu")
			(hatch none 0.5)
			(connect_pads
				(clearance 0)
			)
			(min_thickness 0.25)
			(keepout
				(tracks not_allowed)
				(vias allowed)
				(pads allowed)
				(copperpour not_allowed)
				(footprints allowed)
			)
			(placement
				(enabled no)
				(sheetname "")
			)
			(fill
				(thermal_gap 0.5)
				(thermal_bridge_width 0.5)
				(island_removal_mode 0)
			)
			(polygon
				(pts
					(xy 400.0754 -74.422) (xy 400.0754 -73.914) (xy 399.6944 -73.914) (xy 399.6944 -74.422)
				)
			)
		)
	)
	(footprint ""
		(layer "B.Cu")
		(at 178.562 -51.562 -90)
		(property "Reference" "C6R14"
			(at 0 0 90)
			(layer "B.SilkS")
			(hide yes)
			(effects
				(font
					(size 1.27 1.27)
				)
				(justify mirror)
			)
		)
		(property "Value" ""
			(at 0 0 90)
			(layer "B.Fab")
			(effects
				(font
					(size 1.27 1.27)
				)
				(justify mirror)
			)
		)
		(duplicate_pad_numbers_are_jumpers no)
		(fp_poly
			(pts
				(xy 0.7239 -0.2159) (xy -0.7239 -0.2159) (xy -0.7239 1.9939) (xy 0.7239 1.9939)
			)
			(stroke
				(width 0)
				(type default)
			)
			(fill no)
			(layer "B.CrtYd")
		)
		(fp_line
			(start -0.7239 1.9939)
			(end -0.7239 -0.2159)
			(stroke
				(width 0.1)
				(type default)
			)
			(layer "B.Fab")
		)
		(fp_line
			(start 0.7239 1.9939)
			(end -0.7239 1.9939)
			(stroke
				(width 0.1)
				(type default)
			)
			(layer "B.Fab")
		)
		(fp_line
			(start -0.7239 -0.2159)
			(end 0.7239 -0.2159)
			(stroke
				(width 0.1)
				(type default)
			)
			(layer "B.Fab")
		)
		(fp_line
			(start 0.7239 -0.2159)
			(end 0.7239 1.9939)
			(stroke
				(width 0.1)
				(type default)
			)
			(layer "B.Fab")
		)
		(pad "1" smd rect
			(at 0 0 90)
			(size 1.27 1.016)
			(layers "B.Cu" "B.Mask" "B.Paste")
			(net "VR_FET_SW_P12V_STBY_PVCCIN_CPU0")
		)
		(pad "2" smd rect
			(at 0 1.778 90)
			(size 1.27 1.016)
			(layers "B.Cu" "B.Mask" "B.Paste")
			(net "GND")
		)
		(zone
			(layer "B.Cu")
			(hatch none 0.5)
			(connect_pads
				(clearance 0)
			)
			(min_thickness 0.25)
			(keepout
				(tracks not_allowed)
				(vias allowed)
				(pads allowed)
				(copperpour not_allowed)
				(footprints allowed)
			)
			(placement
				(enabled no)
				(sheetname "")
			)
			(fill
				(thermal_gap 0.5)
				(thermal_bridge_width 0.5)
				(island_removal_mode 0)
			)
			(polygon
				(pts
					(xy 178.054 -50.927) (xy 178.054 -52.197) (xy 177.292 -52.197) (xy 177.292 -50.927)
				)
			)
		)
	)
	(footprint ""
		(layer "B.Cu")
		(at 437.769 -20.193 -90)
		(property "Reference" "Q9W3"
			(at 0.229362 -1.59512 270)
			(unlocked yes)
			(layer "B.SilkS")
			(effects
				(font
					(size 1.27 0.9652)
					(thickness 0.1524)
				)
				(justify left mirror)
			)
		)
		(property "Value" ""
			(at 0 0 90)
			(layer "B.Fab")
			(effects
				(font
					(size 1.27 1.27)
				)
				(justify mirror)
			)
		)
		(duplicate_pad_numbers_are_jumpers no)
		(fp_line
			(start -1.778 2.4765)
			(end -1.778 1.5875)
			(stroke
				(width 0.1524)
				(type default)
			)
			(layer "B.SilkS")
		)
		(fp_line
			(start -0.9525 2.4765)
			(end -1.778 2.4765)
			(stroke
				(width 0.1524)
				(type default)
			)
			(layer "B.SilkS")
		)
		(fp_line
			(start -0.381 0.635)
			(end -0.381 1.27)
			(stroke
				(width 0.1524)
				(type default)
			)
			(layer "B.SilkS")
		)
		(fp_line
			(start -1.778 -0.5715)
			(end -1.778 0.3175)
			(stroke
				(width 0.1524)
				(type default)
			)
			(layer "B.SilkS")
		)
		(fp_line
			(start -0.9525 -0.5715)
			(end -1.778 -0.5715)
			(stroke
				(width 0.1524)
				(type default)
			)
			(layer "B.SilkS")
		)
		(fp_circle
			(center 0.9525 -0.9271)
			(end 0.9525 -1.0541)
			(stroke
				(width 0.254)
				(type default)
			)
			(fill no)
			(layer "B.SilkS")
		)
		(fp_poly
			(pts
				(xy -1.778 2.4765) (xy -0.381 2.4765) (xy -0.381 -0.5715) (xy -1.778 -0.5715)
			)
			(stroke
				(width 0)
				(type default)
			)
			(fill no)
			(layer "B.CrtYd")
		)
		(fp_line
			(start -1.778 2.4765)
			(end -1.778 -0.5715)
			(stroke
				(width 0.1)
				(type default)
			)
			(layer "B.Fab")
		)
		(fp_line
			(start -0.381 2.4765)
			(end -1.778 2.4765)
			(stroke
				(width 0.1)
				(type default)
			)
			(layer "B.Fab")
		)
		(fp_line
			(start -1.778 -0.5715)
			(end -0.381 -0.5715)
			(stroke
				(width 0.1)
				(type default)
			)
			(layer "B.Fab")
		)
		(fp_line
			(start -0.381 -0.5715)
			(end -0.381 2.4765)
			(stroke
				(width 0.1)
				(type default)
			)
			(layer "B.Fab")
		)
		(fp_circle
			(center 0.9525 -0.9271)
			(end 0.9525 -1.0541)
			(stroke
				(width 0.254)
				(type default)
			)
			(fill no)
			(layer "B.Fab")
		)
		(pad "1" smd rect
			(at 0 0 90)
			(size 1.143 0.508)
			(layers "B.Cu" "B.Mask" "B.Paste")
			(net "FM_TPM_PRES_RST")
		)
		(pad "2" smd rect
			(at 0 1.905 90)
			(size 1.143 0.508)
			(layers "B.Cu" "B.Mask" "B.Paste")
			(net "GND")
		)
		(pad "3" smd rect
			(at -2.159 0.9525 90)
			(size 1.143 0.508)
			(layers "B.Cu" "B.Mask" "B.Paste")
			(net "RST_BMC_EXTRST_N")
		)
	)
)
